# T6G (Grand Teton) — schematic netlist excerpt (pin names and nets, part order shuffled) for the footprints in the layout excerpt that follows; sources: Cadence DE-HDL packaged netlist, KiCad conversion of 04192023_DAF0TMB3IC0_F0TG_MB_C_brd_V02_OCP.brd

C1773  Q_CAP  0.1UF 25V 10% X7R  pkg 0402  page 127 : A = BIC_MONITER_ISO ; B = GND
PR226  Q_RES  49.9 1% CHIP  pkg 0402LF  page 217 : A = VSENSE_VSS_SENSE_C_P1 ; B = GND

(kicad_pcb
	(version 20260206)
	(generator "pcbnew")
	(generator_version "10.0")
	(general
		(thickness 1.6)
		(legacy_teardrops no)
	)
	(paper "A4")
	(title_block
		(title "04192023_DAF0TMB3IC0_F0TG_MB_C_brd_V02_OCP.brd")
		(comment 1 "Grand Teton / footprints 2711-2712 of 8354")
	)
	(layers
		(0 "F.Cu" signal "TOP")
		(4 "In1.Cu" signal "GND")
		(6 "In2.Cu" signal "IN1")
		(8 "In3.Cu" signal "GND1")
		(10 "In4.Cu" signal "IN2")
		(12 "In5.Cu" signal "GND2")
		(14 "In6.Cu" signal "IN3")
		(16 "In7.Cu" signal "GND3")
		(18 "In8.Cu" signal "VCC")
		(20 "In9.Cu" signal "VCC1")
		(22 "In10.Cu" signal "GND4")
		(24 "In11.Cu" signal "IN4")
		(26 "In12.Cu" signal "GND5")
		(28 "In13.Cu" signal "IN5")
		(30 "In14.Cu" signal "GND6")
		(32 "In15.Cu" signal "IN6")
		(34 "In16.Cu" signal "GND7")
		(2 "B.Cu" signal "BOTTOM")
		(9 "F.Adhes" user "F.Adhesive")
		(11 "B.Adhes" user "B.Adhesive")
		(13 "F.Paste" user "Package Geometry/Pastemask Top")
		(15 "B.Paste" user "Package Geometry/Pastemask Bottom")
		(5 "F.SilkS" user "Ref Des/Silkscreen Top")
		(7 "B.SilkS" user "Ref Des/Silkscreen Bottom")
		(1 "F.Mask" user "Board Geometry/Soldermask Top")
		(3 "B.Mask" user "Board Geometry/Soldermask Bottom")
		(17 "Dwgs.User" user "User.Drawings")
		(19 "Cmts.User" user "User.Comments")
		(21 "Eco1.User" user "User.Eco1")
		(23 "Eco2.User" user "User.Eco2")
		(25 "Edge.Cuts" user "Board Geometry/Outline")
		(27 "Margin" user)
		(31 "F.CrtYd" user "Package Geometry/Place Bound Top")
		(29 "B.CrtYd" user "Package Geometry/Place Bound Bottom")
		(35 "F.Fab" user "Ref Des/Assembly Top")
		(33 "B.Fab" user "Ref Des/Assembly Bottom")
	)
	(footprint ""
		(layer "F.Cu")
		(at 109.918754 -327.582276 180)
		(property "Reference" "PR226"
			(at 0 0 180)
			(layer "F.SilkS")
			(hide yes)
			(effects
				(font
					(size 1.27 1.27)
				)
			)
		)
		(property "Value" ""
			(at 0 0 180)
			(layer "F.Fab")
			(effects
				(font
					(size 1.27 1.27)
				)
			)
		)
		(duplicate_pad_numbers_are_jumpers no)
		(fp_line
			(start 0.7874 0.4064)
			(end -0.7874 0.4064)
			(stroke
				(width 0.1524)
				(type default)
			)
			(layer "F.SilkS")
		)
		(fp_line
			(start 0.7874 -0.4064)
			(end 0.7874 0.4064)
			(stroke
				(width 0.1524)
				(type default)
			)
			(layer "F.SilkS")
		)
		(fp_line
			(start -0.7874 0.4064)
			(end -0.7874 -0.4064)
			(stroke
				(width 0.1524)
				(type default)
			)
			(layer "F.SilkS")
		)
		(fp_line
			(start -0.7874 -0.4064)
			(end 0.7874 -0.4064)
			(stroke
				(width 0.1524)
				(type default)
			)
			(layer "F.SilkS")
		)
		(fp_line
			(start 0.67945 0.3048)
			(end 0.120396 0.3048)
			(stroke
				(width 0.1)
				(type default)
			)
			(layer "F.Fab")
		)
		(fp_line
			(start 0.67945 -0.3048)
			(end 0.67945 0.3048)
			(stroke
				(width 0.1)
				(type default)
			)
			(layer "F.Fab")
		)
		(fp_line
			(start 0.12065 -0.2794)
			(end 0.12065 -0.3048)
			(stroke
				(width 0.1)
				(type default)
			)
			(layer "F.Fab")
		)
		(fp_line
			(start 0.12065 -0.3048)
			(end 0.67945 -0.3048)
			(stroke
				(width 0.1)
				(type default)
			)
			(layer "F.Fab")
		)
		(fp_line
			(start 0.120396 0.3048)
			(end 0.120396 0.2794)
			(stroke
				(width 0.1)
				(type default)
			)
			(layer "F.Fab")
		)
		(fp_line
			(start 0.120396 0.2794)
			(end -0.12065 0.2794)
			(stroke
				(width 0.1)
				(type default)
			)
			(layer "F.Fab")
		)
		(fp_line
			(start -0.12065 0.3048)
			(end -0.67945 0.3048)
			(stroke
				(width 0.1)
				(type default)
			)
			(layer "F.Fab")
		)
		(fp_line
			(start -0.12065 0.2794)
			(end -0.12065 0.3048)
			(stroke
				(width 0.1)
				(type default)
			)
			(layer "F.Fab")
		)
		(fp_line
			(start -0.12065 -0.2794)
			(end 0.12065 -0.2794)
			(stroke
				(width 0.1)
				(type default)
			)
			(layer "F.Fab")
		)
		(fp_line
			(start -0.12065 -0.305054)
			(end -0.12065 -0.2794)
			(stroke
				(width 0.1)
				(type default)
			)
			(layer "F.Fab")
		)
		(fp_line
			(start -0.67945 0.3048)
			(end -0.67945 -0.305054)
			(stroke
				(width 0.1)
				(type default)
			)
			(layer "F.Fab")
		)
		(fp_line
			(start -0.67945 -0.305054)
			(end -0.12065 -0.305054)
			(stroke
				(width 0.1)
				(type default)
			)
			(layer "F.Fab")
		)
		(pad "1" smd circle
			(at -0.40005 0 180)
			(size 0 0)
			(layers "F.Cu" "F.Mask" "F.Paste")
			(net "VSENSE_VSS_SENSE_C_P1")
		)
		(pad "2" smd circle
			(at 0.40005 0 180)
			(size 0 0)
			(layers "F.Cu" "F.Mask" "F.Paste")
			(net "GND")
		)
	)
	(footprint ""
		(layer "F.Cu")
		(at 165.2016 -438.912)
		(property "Reference" "C1773"
			(at 0 0 0)
			(layer "F.SilkS")
			(hide yes)
			(effects
				(font
					(size 1.27 1.27)
				)
			)
		)
		(property "Value" ""
			(at 0 0 0)
			(layer "F.Fab")
			(effects
				(font
					(size 1.27 1.27)
				)
			)
		)
		(duplicate_pad_numbers_are_jumpers no)
		(fp_line
			(start -0.7874 -0.4064)
			(end 0.7874 -0.4064)
			(stroke
				(width 0.1524)
				(type default)
			)
			(layer "F.SilkS")
		)
		(fp_line
			(start -0.7874 0.4064)
			(end -0.7874 -0.4064)
			(stroke
				(width 0.1524)
				(type default)
			)
			(layer "F.SilkS")
		)
		(fp_line
			(start 0.7874 -0.4064)
			(end 0.7874 0.4064)
			(stroke
				(width 0.1524)
				(type default)
			)
			(layer "F.SilkS")
		)
		(fp_line
			(start 0.7874 0.4064)
			(end -0.7874 0.4064)
			(stroke
				(width 0.1524)
				(type default)
			)
			(layer "F.SilkS")
		)
		(fp_line
			(start -0.67945 -0.305054)
			(end -0.12065 -0.305054)
			(stroke
				(width 0.1)
				(type default)
			)
			(layer "F.Fab")
		)
		(fp_line
			(start -0.67945 0.3048)
			(end -0.67945 -0.305054)
			(stroke
				(width 0.1)
				(type default)
			)
			(layer "F.Fab")
		)
		(fp_line
			(start -0.12065 -0.305054)
			(end -0.12065 -0.2794)
			(stroke
				(width 0.1)
				(type default)
			)
			(layer "F.Fab")
		)
		(fp_line
			(start -0.12065 -0.2794)
			(end 0.12065 -0.2794)
			(stroke
				(width 0.1)
				(type default)
			)
			(layer "F.Fab")
		)
		(fp_line
			(start -0.12065 0.2794)
			(end -0.12065 0.3048)
			(stroke
				(width 0.1)
				(type default)
			)
			(layer "F.Fab")
		)
		(fp_line
			(start -0.12065 0.3048)
			(end -0.67945 0.3048)
			(stroke
				(width 0.1)
				(type default)
			)
			(layer "F.Fab")
		)
		(fp_line
			(start 0.120396 0.2794)
			(end -0.12065 0.2794)
			(stroke
				(width 0.1)
				(type default)
			)
			(layer "F.Fab")
		)
		(fp_line
			(start 0.120396 0.3048)
			(end 0.120396 0.2794)
			(stroke
				(width 0.1)
				(type default)
			)
			(layer "F.Fab")
		)
		(fp_line
			(start 0.12065 -0.3048)
			(end 0.67945 -0.3048)
			(stroke
				(width 0.1)
				(type default)
			)
			(layer "F.Fab")
		)
		(fp_line
			(start 0.12065 -0.2794)
			(end 0.12065 -0.3048)
			(stroke
				(width 0.1)
				(type default)
			)
			(layer "F.Fab")
		)
		(fp_line
			(start 0.67945 -0.3048)
			(end 0.67945 0.3048)
			(stroke
				(width 0.1)
				(type default)
			)
			(layer "F.Fab")
		)
		(fp_line
			(start 0.67945 0.3048)
			(end 0.120396 0.3048)
			(stroke
				(width 0.1)
				(type default)
			)
			(layer "F.Fab")
		)
		(pad "1" smd circle
			(at -0.40005 0)
			(size 0 0)
			(layers "F.Cu" "F.Mask" "F.Paste")
			(net "BIC_MONITER_ISO")
		)
		(pad "2" smd circle
			(at 0.40005 0)
			(size 0 0)
			(layers "F.Cu" "F.Mask" "F.Paste")
			(net "GND")
		)
	)
)
